# T6G (Grand Teton) — schematic netlist excerpt (pin names and nets, part order shuffled) for the footprints in the layout excerpt that follows; sources: Cadence DE-HDL packaged netlist, KiCad conversion of 04192023_DAF0TMB3IC0_F0TG_MB_C_brd_V02_OCP.brd

R6001  Q_RES  0 5% CHIP  pkg 0402LF  page 150 : A = I3C_SCM_0_SDA ; B = I3C_SCM_0_R_SDA
R1550  Q_RES  33 5% CHIP  pkg 0402LF  page 81 : A = ESPI_CPU0_R1_D1 ; B = ESPI_CPU0_D1

(kicad_pcb
	(version 20260206)
	(generator "pcbnew")
	(generator_version "10.0")
	(general
		(thickness 1.6)
		(legacy_teardrops no)
	)
	(paper "A4")
	(title_block
		(title "04192023_DAF0TMB3IC0_F0TG_MB_C_brd_V02_OCP.brd")
		(comment 1 "Grand Teton / footprints 6776-6777 of 8354")
	)
	(layers
		(0 "F.Cu" signal "TOP")
		(4 "In1.Cu" signal "GND")
		(6 "In2.Cu" signal "IN1")
		(8 "In3.Cu" signal "GND1")
		(10 "In4.Cu" signal "IN2")
		(12 "In5.Cu" signal "GND2")
		(14 "In6.Cu" signal "IN3")
		(16 "In7.Cu" signal "GND3")
		(18 "In8.Cu" signal "VCC")
		(20 "In9.Cu" signal "VCC1")
		(22 "In10.Cu" signal "GND4")
		(24 "In11.Cu" signal "IN4")
		(26 "In12.Cu" signal "GND5")
		(28 "In13.Cu" signal "IN5")
		(30 "In14.Cu" signal "GND6")
		(32 "In15.Cu" signal "IN6")
		(34 "In16.Cu" signal "GND7")
		(2 "B.Cu" signal "BOTTOM")
		(9 "F.Adhes" user "F.Adhesive")
		(11 "B.Adhes" user "B.Adhesive")
		(13 "F.Paste" user "Package Geometry/Pastemask Top")
		(15 "B.Paste" user "Package Geometry/Pastemask Bottom")
		(5 "F.SilkS" user "Ref Des/Silkscreen Top")
		(7 "B.SilkS" user "Ref Des/Silkscreen Bottom")
		(1 "F.Mask" user "Board Geometry/Soldermask Top")
		(3 "B.Mask" user "Board Geometry/Soldermask Bottom")
		(17 "Dwgs.User" user "User.Drawings")
		(19 "Cmts.User" user "User.Comments")
		(21 "Eco1.User" user "User.Eco1")
		(23 "Eco2.User" user "User.Eco2")
		(25 "Edge.Cuts" user "Board Geometry/Outline")
		(27 "Margin" user)
		(31 "F.CrtYd" user "Package Geometry/Place Bound Top")
		(29 "B.CrtYd" user "Package Geometry/Place Bound Bottom")
		(35 "F.Fab" user "Ref Des/Assembly Top")
		(33 "B.Fab" user "Ref Des/Assembly Bottom")
	)
	(footprint ""
		(layer "B.Cu")
		(at 189.35065 -13.60043 -90)
		(property "Reference" "R6001"
			(at 0 0 90)
			(layer "B.SilkS")
			(hide yes)
			(effects
				(font
					(size 1.27 1.27)
				)
				(justify mirror)
			)
		)
		(property "Value" ""
			(at 0 0 90)
			(layer "B.Fab")
			(effects
				(font
					(size 1.27 1.27)
				)
				(justify mirror)
			)
		)
		(duplicate_pad_numbers_are_jumpers no)
		(fp_line
			(start -0.7874 0.4064)
			(end 0.7874 0.4064)
			(stroke
				(width 0.1524)
				(type default)
			)
			(layer "B.SilkS")
		)
		(fp_line
			(start 0.7874 0.4064)
			(end 0.7874 -0.4064)
			(stroke
				(width 0.1524)
				(type default)
			)
			(layer "B.SilkS")
		)
		(fp_line
			(start -0.7874 -0.4064)
			(end -0.7874 0.4064)
			(stroke
				(width 0.1524)
				(type default)
			)
			(layer "B.SilkS")
		)
		(fp_line
			(start 0.7874 -0.4064)
			(end -0.7874 -0.4064)
			(stroke
				(width 0.1524)
				(type default)
			)
			(layer "B.SilkS")
		)
		(fp_line
			(start -0.67945 0.3048)
			(end -0.120396 0.3048)
			(stroke
				(width 0.1)
				(type default)
			)
			(layer "B.Fab")
		)
		(fp_line
			(start -0.120396 0.3048)
			(end -0.120396 0.2794)
			(stroke
				(width 0.1)
				(type default)
			)
			(layer "B.Fab")
		)
		(fp_line
			(start 0.12065 0.3048)
			(end 0.67945 0.3048)
			(stroke
				(width 0.1)
				(type default)
			)
			(layer "B.Fab")
		)
		(fp_line
			(start 0.67945 0.3048)
			(end 0.67945 -0.305054)
			(stroke
				(width 0.1)
				(type default)
			)
			(layer "B.Fab")
		)
		(fp_line
			(start -0.120396 0.2794)
			(end 0.12065 0.2794)
			(stroke
				(width 0.1)
				(type default)
			)
			(layer "B.Fab")
		)
		(fp_line
			(start 0.12065 0.2794)
			(end 0.12065 0.3048)
			(stroke
				(width 0.1)
				(type default)
			)
			(layer "B.Fab")
		)
		(fp_line
			(start -0.12065 -0.2794)
			(end -0.12065 -0.3048)
			(stroke
				(width 0.1)
				(type default)
			)
			(layer "B.Fab")
		)
		(fp_line
			(start 0.12065 -0.2794)
			(end -0.12065 -0.2794)
			(stroke
				(width 0.1)
				(type default)
			)
			(layer "B.Fab")
		)
		(fp_line
			(start -0.67945 -0.3048)
			(end -0.67945 0.3048)
			(stroke
				(width 0.1)
				(type default)
			)
			(layer "B.Fab")
		)
		(fp_line
			(start -0.12065 -0.3048)
			(end -0.67945 -0.3048)
			(stroke
				(width 0.1)
				(type default)
			)
			(layer "B.Fab")
		)
		(fp_line
			(start 0.12065 -0.305054)
			(end 0.12065 -0.2794)
			(stroke
				(width 0.1)
				(type default)
			)
			(layer "B.Fab")
		)
		(fp_line
			(start 0.67945 -0.305054)
			(end 0.12065 -0.305054)
			(stroke
				(width 0.1)
				(type default)
			)
			(layer "B.Fab")
		)
		(pad "1" smd circle
			(at 0.40005 0 90)
			(size 0 0)
			(layers "B.Cu" "B.Mask" "B.Paste")
			(net "I3C_SCM_0_SDA")
		)
		(pad "2" smd circle
			(at -0.40005 0 90)
			(size 0 0)
			(layers "B.Cu" "B.Mask" "B.Paste")
			(net "I3C_SCM_0_R_SDA")
		)
	)
	(footprint ""
		(layer "B.Cu")
		(at 189.087506 -126.833376 -90)
		(property "Reference" "R1550"
			(at 0 0 90)
			(layer "B.SilkS")
			(hide yes)
			(effects
				(font
					(size 1.27 1.27)
				)
				(justify mirror)
			)
		)
		(property "Value" ""
			(at 0 0 90)
			(layer "B.Fab")
			(effects
				(font
					(size 1.27 1.27)
				)
				(justify mirror)
			)
		)
		(duplicate_pad_numbers_are_jumpers no)
		(fp_line
			(start -0.7874 0.4064)
			(end 0.7874 0.4064)
			(stroke
				(width 0.1524)
				(type default)
			)
			(layer "B.SilkS")
		)
		(fp_line
			(start 0.7874 0.4064)
			(end 0.7874 -0.4064)
			(stroke
				(width 0.1524)
				(type default)
			)
			(layer "B.SilkS")
		)
		(fp_line
			(start -0.7874 -0.4064)
			(end -0.7874 0.4064)
			(stroke
				(width 0.1524)
				(type default)
			)
			(layer "B.SilkS")
		)
		(fp_line
			(start 0.7874 -0.4064)
			(end -0.7874 -0.4064)
			(stroke
				(width 0.1524)
				(type default)
			)
			(layer "B.SilkS")
		)
		(fp_line
			(start -0.67945 0.3048)
			(end -0.120396 0.3048)
			(stroke
				(width 0.1)
				(type default)
			)
			(layer "B.Fab")
		)
		(fp_line
			(start -0.120396 0.3048)
			(end -0.120396 0.2794)
			(stroke
				(width 0.1)
				(type default)
			)
			(layer "B.Fab")
		)
		(fp_line
			(start 0.12065 0.3048)
			(end 0.67945 0.3048)
			(stroke
				(width 0.1)
				(type default)
			)
			(layer "B.Fab")
		)
		(fp_line
			(start 0.67945 0.3048)
			(end 0.67945 -0.305054)
			(stroke
				(width 0.1)
				(type default)
			)
			(layer "B.Fab")
		)
		(fp_line
			(start -0.120396 0.2794)
			(end 0.12065 0.2794)
			(stroke
				(width 0.1)
				(type default)
			)
			(layer "B.Fab")
		)
		(fp_line
			(start 0.12065 0.2794)
			(end 0.12065 0.3048)
			(stroke
				(width 0.1)
				(type default)
			)
			(layer "B.Fab")
		)
		(fp_line
			(start -0.12065 -0.2794)
			(end -0.12065 -0.3048)
			(stroke
				(width 0.1)
				(type default)
			)
			(layer "B.Fab")
		)
		(fp_line
			(start 0.12065 -0.2794)
			(end -0.12065 -0.2794)
			(stroke
				(width 0.1)
				(type default)
			)
			(layer "B.Fab")
		)
		(fp_line
			(start -0.67945 -0.3048)
			(end -0.67945 0.3048)
			(stroke
				(width 0.1)
				(type default)
			)
			(layer "B.Fab")
		)
		(fp_line
			(start -0.12065 -0.3048)
			(end -0.67945 -0.3048)
			(stroke
				(width 0.1)
				(type default)
			)
			(layer "B.Fab")
		)
		(fp_line
			(start 0.12065 -0.305054)
			(end 0.12065 -0.2794)
			(stroke
				(width 0.1)
				(type default)
			)
			(layer "B.Fab")
		)
		(fp_line
			(start 0.67945 -0.305054)
			(end 0.12065 -0.305054)
			(stroke
				(width 0.1)
				(type default)
			)
			(layer "B.Fab")
		)
		(pad "1" smd circle
			(at 0.40005 0 90)
			(size 0 0)
			(layers "B.Cu" "B.Mask" "B.Paste")
			(net "ESPI_CPU0_R1_D1")
		)
		(pad "2" smd circle
			(at -0.40005 0 90)
			(size 0 0)
			(layers "B.Cu" "B.Mask" "B.Paste")
			(net "ESPI_CPU0_D1")
		)
	)
)
